FILE_TYPE = MULTI_PHYS_TABLE;

PART 'DIODE_3F'
CLASS=DISCRETE

{========================================================================================}
:CLS_PN          = JEDEC_TYPE      | ALT_SYMBOLS       | DESCRIPTION                              | CPN_STATUS ;
{========================================================================================}
 'G122-10048-01' = 'SOT23_V1_H045' | '(SOT23_V1_H045)' | 'DIO, SIGNAL ZENER, DUAL, 30V, SOT23'    | ''        
 'G122-10151-01' = 'SOT23_V1_H044' | '(SOT23_V1_H044)' | 'DIO,TVS,SDC15,300W,10A,14.3V,SOT23'     | ''        
 'G122-10080-01' = 'DPAK_3_V3'     | '(DPAK_3_V3)'     | 'DIO,SCHOTTKY,V20W60C-M3,60V,20A,TO-252' | ''

END_PART

END.

